# BASEBOARD_FAB2 (Tioga Pass) — schematic netlist excerpt (pin names and nets, part order shuffled) for the footprints in the layout excerpt that follows; sources: Cadence DE-HDL packaged netlist, KiCad conversion of Wiwynn_Tioga_Pass_MB.brd

C5G106  CAP_A  22.0UF 4V 20% X6S  pkg 0603V  page 243 : A = PVDDQ_KLM ; B = GND
C5P14  CAP  47UF 4V 20% X6S  pkg 0805  page 42 : A = PVCCIN_CPU0 ; B = GND
C4G25  CAP_A  0.1UF 16V 10% X7R  pkg 0402V  page 99 : A = PVPP_GHJ ; B = GND

(kicad_pcb
	(version 20260206)
	(generator "pcbnew")
	(generator_version "10.0")
	(general
		(thickness 1.6)
		(legacy_teardrops no)
	)
	(paper "A4")
	(title_block
		(title "Wiwynn_Tioga_Pass_MB.brd")
		(comment 1 "Tioga Pass / footprints 3225-3227 of 4770")
	)
	(layers
		(0 "F.Cu" signal "TOP")
		(4 "In1.Cu" signal "L2GND")
		(6 "In2.Cu" signal "L3")
		(8 "In3.Cu" signal "L4GND")
		(10 "In4.Cu" signal "L5")
		(12 "In5.Cu" signal "L6GND")
		(14 "In6.Cu" signal "L7VCC")
		(16 "In7.Cu" signal "L8VCC")
		(18 "In8.Cu" signal "L9GND")
		(20 "In9.Cu" signal "L10")
		(22 "In10.Cu" signal "L11GND")
		(24 "In11.Cu" signal "L12")
		(26 "In12.Cu" signal "L13GND")
		(2 "B.Cu" signal "BOTTOM")
		(9 "F.Adhes" user "F.Adhesive")
		(11 "B.Adhes" user "B.Adhesive")
		(13 "F.Paste" user "Package Geometry/Pastemask Top")
		(15 "B.Paste" user "Package Geometry/Pastemask Bottom")
		(5 "F.SilkS" user "Ref Des/Silkscreen Top")
		(7 "B.SilkS" user "Ref Des/Silkscreen Bottom")
		(1 "F.Mask" user "Board Geometry/Soldermask Top")
		(3 "B.Mask" user "Board Geometry/Soldermask Bottom")
		(17 "Dwgs.User" user "User.Drawings")
		(19 "Cmts.User" user "User.Comments")
		(21 "Eco1.User" user "User.Eco1")
		(23 "Eco2.User" user "User.Eco2")
		(25 "Edge.Cuts" user "Board Geometry/Outline")
		(27 "Margin" user)
		(31 "F.CrtYd" user "Package Geometry/Place Bound Top")
		(29 "B.CrtYd" user "Package Geometry/Place Bound Bottom")
		(35 "F.Fab" user "Ref Des/Assembly Top")
		(33 "B.Fab" user "Ref Des/Assembly Bottom")
	)
	(footprint ""
		(layer "B.Cu")
		(at 101.3968 -140.208 90)
		(property "Reference" "C5G106"
			(at -1.14681 0.76708 180)
			(unlocked yes)
			(layer "B.SilkS")
			(effects
				(font
					(size 0.7874 0.5842)
					(thickness 0.1524)
				)
				(justify mirror)
			)
		)
		(property "Value" ""
			(at 0 0 90)
			(layer "B.Fab")
			(effects
				(font
					(size 1.27 1.27)
				)
				(justify mirror)
			)
		)
		(duplicate_pad_numbers_are_jumpers no)
		(fp_rect
			(start -0.4953 -0.2032)
			(end 0.4953 1.6002)
			(stroke
				(width 0)
				(type default)
			)
			(fill no)
			(layer "B.CrtYd")
		)
		(fp_line
			(start 0.4953 -0.2032)
			(end -0.4953 -0.2032)
			(stroke
				(width 0.1)
				(type default)
			)
			(layer "B.Fab")
		)
		(fp_line
			(start -0.4953 -0.2032)
			(end -0.4953 1.6002)
			(stroke
				(width 0.1)
				(type default)
			)
			(layer "B.Fab")
		)
		(fp_line
			(start 0.4953 1.6002)
			(end 0.4953 -0.2032)
			(stroke
				(width 0.1)
				(type default)
			)
			(layer "B.Fab")
		)
		(fp_line
			(start -0.4953 1.6002)
			(end 0.4953 1.6002)
			(stroke
				(width 0.1)
				(type default)
			)
			(layer "B.Fab")
		)
		(pad "1" smd rect
			(at 0 0 270)
			(size 0.762 0.889)
			(layers "B.Cu" "B.Mask" "B.Paste")
			(net "PVDDQ_KLM")
		)
		(pad "2" smd rect
			(at 0 1.397 270)
			(size 0.762 0.889)
			(layers "B.Cu" "B.Mask" "B.Paste")
			(net "GND")
		)
		(zone
			(layer "B.Cu")
			(hatch none 0.5)
			(connect_pads
				(clearance 0)
			)
			(min_thickness 0.25)
			(keepout
				(tracks not_allowed)
				(vias allowed)
				(pads allowed)
				(copperpour not_allowed)
				(footprints allowed)
			)
			(placement
				(enabled no)
				(sheetname "")
			)
			(fill
				(thermal_gap 0.5)
				(thermal_bridge_width 0.5)
				(island_removal_mode 0)
			)
			(polygon
				(pts
					(xy 101.8413 -139.827) (xy 102.3493 -139.827) (xy 102.3493 -140.589) (xy 101.8413 -140.589)
				)
			)
		)
	)
	(footprint ""
		(layer "B.Cu")
		(at 268.073886 -79.60614 180)
		(property "Reference" "C5P14"
			(at 0 0 0)
			(layer "B.SilkS")
			(hide yes)
			(effects
				(font
					(size 1.27 1.27)
				)
				(justify mirror)
			)
		)
		(property "Value" ""
			(at 0 0 0)
			(layer "B.Fab")
			(effects
				(font
					(size 1.27 1.27)
				)
				(justify mirror)
			)
		)
		(duplicate_pad_numbers_are_jumpers no)
		(fp_poly
			(pts
				(xy 0.7239 -0.2159) (xy -0.7239 -0.2159) (xy -0.7239 1.9939) (xy 0.7239 1.9939)
			)
			(stroke
				(width 0)
				(type default)
			)
			(fill no)
			(layer "B.CrtYd")
		)
		(fp_line
			(start 0.7239 1.9939)
			(end -0.7239 1.9939)
			(stroke
				(width 0.1)
				(type default)
			)
			(layer "B.Fab")
		)
		(fp_line
			(start 0.7239 -0.2159)
			(end 0.7239 1.9939)
			(stroke
				(width 0.1)
				(type default)
			)
			(layer "B.Fab")
		)
		(fp_line
			(start -0.7239 1.9939)
			(end -0.7239 -0.2159)
			(stroke
				(width 0.1)
				(type default)
			)
			(layer "B.Fab")
		)
		(fp_line
			(start -0.7239 -0.2159)
			(end 0.7239 -0.2159)
			(stroke
				(width 0.1)
				(type default)
			)
			(layer "B.Fab")
		)
		(pad "1" smd rect
			(at 0 0)
			(size 1.27 1.016)
			(layers "B.Cu" "B.Mask" "B.Paste")
			(net "PVCCIN_CPU0")
		)
		(pad "2" smd rect
			(at 0 1.778)
			(size 1.27 1.016)
			(layers "B.Cu" "B.Mask" "B.Paste")
			(net "GND")
		)
		(zone
			(layer "B.Cu")
			(hatch none 0.5)
			(connect_pads
				(clearance 0)
			)
			(min_thickness 0.25)
			(keepout
				(tracks not_allowed)
				(vias allowed)
				(pads allowed)
				(copperpour not_allowed)
				(footprints allowed)
			)
			(placement
				(enabled no)
				(sheetname "")
			)
			(fill
				(thermal_gap 0.5)
				(thermal_bridge_width 0.5)
				(island_removal_mode 0)
			)
			(polygon
				(pts
					(xy 267.438886 -80.11414) (xy 268.708886 -80.11414) (xy 268.708886 -80.87614) (xy 267.438886 -80.87614)
				)
			)
		)
	)
	(footprint ""
		(layer "B.Cu")
		(at 165.1127 4.5212 180)
		(property "Reference" "C4G25"
			(at 0 0 0)
			(layer "B.SilkS")
			(hide yes)
			(effects
				(font
					(size 1.27 1.27)
				)
				(justify mirror)
			)
		)
		(property "Value" ""
			(at 0 0 0)
			(layer "B.Fab")
			(effects
				(font
					(size 1.27 1.27)
				)
				(justify mirror)
			)
		)
		(duplicate_pad_numbers_are_jumpers no)
		(fp_poly
			(pts
				(xy -0.3048 -0.1016) (xy -0.3048 0.9906) (xy 0.3048 0.9906) (xy 0.3048 -0.1016)
			)
			(stroke
				(width 0)
				(type default)
			)
			(fill no)
			(layer "B.CrtYd")
		)
		(fp_line
			(start 0.3048 0.9906)
			(end -0.3048 0.9906)
			(stroke
				(width 0.1)
				(type default)
			)
			(layer "B.Fab")
		)
		(fp_line
			(start 0.3048 -0.1016)
			(end 0.3048 0.9906)
			(stroke
				(width 0.1)
				(type default)
			)
			(layer "B.Fab")
		)
		(fp_line
			(start -0.3048 0.9906)
			(end -0.3048 -0.1016)
			(stroke
				(width 0.1)
				(type default)
			)
			(layer "B.Fab")
		)
		(fp_line
			(start -0.3048 -0.1016)
			(end 0.3048 -0.1016)
			(stroke
				(width 0.1)
				(type default)
			)
			(layer "B.Fab")
		)
		(pad "1" smd rect
			(at 0 0)
			(size 0.508 0.508)
			(layers "B.Cu" "B.Mask" "B.Paste")
			(net "PVPP_GHJ")
		)
		(pad "2" smd rect
			(at 0 0.889)
			(size 0.508 0.508)
			(layers "B.Cu" "B.Mask" "B.Paste")
			(net "GND")
		)
		(zone
			(layer "B.Cu")
			(hatch none 0.5)
			(connect_pads
				(clearance 0)
			)
			(min_thickness 0.25)
			(keepout
				(tracks not_allowed)
				(vias allowed)
				(pads allowed)
				(copperpour not_allowed)
				(footprints allowed)
			)
			(placement
				(enabled no)
				(sheetname "")
			)
			(fill
				(thermal_gap 0.5)
				(thermal_bridge_width 0.5)
				(island_removal_mode 0)
			)
			(polygon
				(pts
					(xy 164.8587 3.8862) (xy 165.3667 3.8862) (xy 165.3667 4.2672) (xy 164.8587 4.2672)
				)
			)
		)
		(zone
			(layer "B.Cu")
			(hatch none 0.5)
			(connect_pads
				(clearance 0)
			)
			(min_thickness 0.25)
			(keepout
				(tracks allowed)
				(vias not_allowed)
				(pads allowed)
				(copperpour not_allowed)
				(footprints allowed)
			)
			(placement
				(enabled no)
				(sheetname "")
			)
			(fill
				(thermal_gap 0.5)
				(thermal_bridge_width 0.5)
				(island_removal_mode 0)
			)
			(polygon
				(pts
					(xy 164.8587 4.2672) (xy 165.3667 4.2672) (xy 165.3667 3.8862) (xy 164.8587 3.8862)
				)
			)
		)
	)
)
